(kicad_pcb
	(version 20241229)
	(generator "pcbnew")
	(generator_version "9.0")
	(general
		(thickness 1.294)
		(legacy_teardrops no)
	)
	(paper "A3")
	(title_block
		(title "Kintex 410T devboard")
		(date "2024-04-03")
		(rev "1.1.2")
		(comment 9 "footprints 187-191 of 975")
	)
	(layers
		(0 "F.Cu" mixed)
		(4 "In1.Cu" power)
		(6 "In2.Cu" power)
		(8 "In3.Cu" mixed)
		(10 "In4.Cu" power)
		(12 "In5.Cu" mixed)
		(14 "In6.Cu" power)
		(16 "In7.Cu" mixed)
		(18 "In8.Cu" power)
		(2 "B.Cu" mixed)
		(9 "F.Adhes" user "F.Adhesive")
		(11 "B.Adhes" user "B.Adhesive")
		(13 "F.Paste" user)
		(15 "B.Paste" user)
		(5 "F.SilkS" user "F.Silkscreen")
		(7 "B.SilkS" user "B.Silkscreen")
		(1 "F.Mask" user)
		(3 "B.Mask" user)
		(17 "Dwgs.User" user "User.Drawings")
		(19 "Cmts.User" user "User.Comments")
		(21 "Eco1.User" user "User.Eco1")
		(23 "Eco2.User" user "User.Eco2")
		(25 "Edge.Cuts" user)
		(27 "Margin" user)
		(31 "F.CrtYd" user "F.Courtyard")
		(29 "B.CrtYd" user "B.Courtyard")
		(35 "F.Fab" user)
		(33 "B.Fab" user)
	)
	(footprint "antmicro-footprints:R_0402_1005Metric"
		(layer "F.Cu")
		(at 224.8 162.35 180)
		(descr "Resistor SMD 0402")
		(tags "resistor SMD 0402")
		(property "Reference" "R54"
			(at 1.15 0.3 180)
			(layer "F.SilkS")
			(effects
				(font
					(size 0.7 0.7)
					(thickness 0.15)
				)
				(justify left bottom)
			)
		)
		(property "Value" "R_100R_0402"
			(at 0 1.4 180)
			(layer "F.Fab")
			(effects
				(font
					(size 0.7 0.7)
					(thickness 0.15)
				)
				(justify left bottom)
			)
		)
		(property "Description" "SMD Chip Resistor, 100 ohm, ± 1%, 62.5 mW, 0402 [1005 Metric], Thick Film, General Purpose"
			(at 0 0 180)
			(layer "F.Fab")
			(hide yes)
			(effects
				(font
					(size 1.27 1.27)
					(thickness 0.15)
				)
			)
		)
		(property "Author" "Antmicro"
			(at 449.6 324.7 0)
			(layer "F.Fab")
			(hide yes)
			(effects
				(font
					(size 1 1)
					(thickness 0.15)
				)
			)
		)
		(property "License" "Apache-2.0"
			(at 449.6 324.7 0)
			(layer "F.Fab")
			(hide yes)
			(effects
				(font
					(size 1 1)
					(thickness 0.15)
				)
			)
		)
		(property "MPN" "CR0402-FX-1000GLF"
			(at 449.6 324.7 0)
			(layer "F.Fab")
			(hide yes)
			(effects
				(font
					(size 1 1)
					(thickness 0.15)
				)
			)
		)
		(property "Manufacturer" "Bourns"
			(at 449.6 324.7 0)
			(layer "F.Fab")
			(hide yes)
			(effects
				(font
					(size 1 1)
					(thickness 0.15)
				)
			)
		)
		(property "Tolerance" "1%"
			(at 449.6 324.7 0)
			(layer "F.Fab")
			(hide yes)
			(effects
				(font
					(size 1 1)
					(thickness 0.15)
				)
			)
		)
		(property "Val" "100R"
			(at 449.6 324.7 0)
			(layer "F.Fab")
			(hide yes)
			(effects
				(font
					(size 1 1)
					(thickness 0.15)
				)
			)
		)
		(sheetname "Power supply")
		(sheetfile "power-supply.kicad_sch")
		(attr smd)
		(fp_rect
			(start -0.925 -0.47)
			(end 0.925 0.47)
			(stroke
				(width 0.05)
				(type default)
			)
			(fill no)
			(layer "F.CrtYd")
		)
		(fp_rect
			(start -0.5 -0.25)
			(end 0.5 0.25)
			(stroke
				(width 0.15)
				(type solid)
			)
			(fill no)
			(layer "F.Fab")
		)
		(pad "1" smd roundrect
			(at -0.48 0 180)
			(size 0.59 0.64)
			(layers "F.Cu" "F.Mask" "F.Paste")
			(roundrect_rratio 0.25)
			(net 872 "/Power supply/SINK_EN")
			(pintype "passive")
		)
		(pad "2" smd roundrect
			(at 0.48 0 180)
			(size 0.59 0.64)
			(layers "F.Cu" "F.Mask" "F.Paste")
			(roundrect_rratio 0.25)
			(net 1227 "Net-(C198-Pad2)")
			(pintype "passive")
		)
	)
	(footprint "antmicro-footprints:C_0402_1005Metric"
		(layer "F.Cu")
		(at 154.225 152.4 180)
		(descr "Capacitor SMD 0402")
		(tags "capacitor SMD 0402")
		(property "Reference" "C356"
			(at 0.875 -0.4 0)
			(layer "F.SilkS")
			(effects
				(font
					(size 0.7 0.7)
					(thickness 0.15)
				)
				(justify right bottom)
			)
		)
		(property "Value" "C_100n_0402"
			(at 0 1.4 0)
			(layer "F.Fab")
			(effects
				(font
					(size 0.7 0.7)
					(thickness 0.15)
				)
				(justify right bottom)
			)
		)
		(property "Description" "SMD Multilayer Ceramic Capacitor, 0.1 µF, 50 V, 0402 [1005 Metric], ± 10%, X5R, GRM Series"
			(at 0 0 180)
			(layer "F.Fab")
			(hide yes)
			(effects
				(font
					(size 1.27 1.27)
					(thickness 0.15)
				)
			)
		)
		(property "Author" "Antmicro"
			(at 308.45 304.8 0)
			(layer "F.Fab")
			(hide yes)
			(effects
				(font
					(size 1 1)
					(thickness 0.15)
				)
			)
		)
		(property "Dielectric" "X5R"
			(at 308.45 304.8 0)
			(layer "F.Fab")
			(hide yes)
			(effects
				(font
					(size 1 1)
					(thickness 0.15)
				)
			)
		)
		(property "License" "Apache-2.0"
			(at 308.45 304.8 0)
			(layer "F.Fab")
			(hide yes)
			(effects
				(font
					(size 1 1)
					(thickness 0.15)
				)
			)
		)
		(property "MPN" "GRM155R61H104KE14D"
			(at 308.45 304.8 0)
			(layer "F.Fab")
			(hide yes)
			(effects
				(font
					(size 1 1)
					(thickness 0.15)
				)
			)
		)
		(property "Manufacturer" "Murata"
			(at 308.45 304.8 0)
			(layer "F.Fab")
			(hide yes)
			(effects
				(font
					(size 1 1)
					(thickness 0.15)
				)
			)
		)
		(property "Val" "100n"
			(at 308.45 304.8 0)
			(layer "F.Fab")
			(hide yes)
			(effects
				(font
					(size 1 1)
					(thickness 0.15)
				)
			)
		)
		(property "Voltage" "50V"
			(at 308.45 304.8 0)
			(layer "F.Fab")
			(hide yes)
			(effects
				(font
					(size 1 1)
					(thickness 0.15)
				)
			)
		)
		(sheetname "DC-DC Converters")
		(sheetfile "dc-dc.kicad_sch")
		(attr smd)
		(fp_rect
			(start -0.925 -0.47)
			(end 0.925 0.47)
			(stroke
				(width 0.05)
				(type default)
			)
			(fill no)
			(layer "F.CrtYd")
		)
		(fp_line
			(start 0.504 0.248)
			(end -0.494 0.248)
			(stroke
				(width 0.15)
				(type solid)
			)
			(layer "F.Fab")
		)
		(fp_line
			(start 0.504 -0.25)
			(end 0.504 0.248)
			(stroke
				(width 0.15)
				(type solid)
			)
			(layer "F.Fab")
		)
		(fp_line
			(start -0.494 0.248)
			(end -0.494 -0.25)
			(stroke
				(width 0.15)
				(type solid)
			)
			(layer "F.Fab")
		)
		(fp_line
			(start -0.494 -0.25)
			(end 0.504 -0.25)
			(stroke
				(width 0.15)
				(type solid)
			)
			(layer "F.Fab")
		)
		(pad "1" smd roundrect
			(at -0.48 0 180)
			(size 0.59 0.64)
			(layers "F.Cu" "F.Mask" "F.Paste")
			(roundrect_rratio 0.25)
			(net 1 "GND")
			(pintype "passive")
		)
		(pad "2" smd roundrect
			(at 0.48 0 180)
			(size 0.59 0.64)
			(layers "F.Cu" "F.Mask" "F.Paste")
			(roundrect_rratio 0.25)
			(net 11 "+0V675_VREF")
			(pintype "passive")
		)
	)
	(footprint "antmicro-footprints:NetTie-2_SMD_Pad0.127mm"
		(layer "F.Cu")
		(at 189.1 146.59 180)
		(descr "Net tie, 2 pin, 0.127mm  SMD pads")
		(tags "net tie")
		(property "Reference" "NT27"
			(at -0.128 -1.345 180)
			(layer "F.SilkS")
			(hide yes)
			(effects
				(font
					(size 0.7 0.7)
					(thickness 0.15)
				)
				(justify left bottom)
			)
		)
		(property "Value" "Net-Tie_2"
			(at 0 1.199 180)
			(layer "F.Fab")
			(effects
				(font
					(size 0.7 0.7)
					(thickness 0.15)
				)
				(justify left bottom)
			)
		)
		(property "Description" "Net tie, 2 pins"
			(at 0 0 180)
			(layer "F.Fab")
			(hide yes)
			(effects
				(font
					(size 1.27 1.27)
					(thickness 0.15)
				)
			)
		)
		(property "Author" "Antmicro"
			(at 378.2 293.18 0)
			(layer "F.Fab")
			(hide yes)
			(effects
				(font
					(size 1 1)
					(thickness 0.15)
				)
			)
		)
		(property "License" "Apache-2.0"
			(at 378.2 293.18 0)
			(layer "F.Fab")
			(hide yes)
			(effects
				(font
					(size 1 1)
					(thickness 0.15)
				)
			)
		)
		(property "MPN" ""
			(at 378.2 293.18 0)
			(layer "F.Fab")
			(hide yes)
			(effects
				(font
					(size 1 1)
					(thickness 0.15)
				)
			)
		)
		(property "Manufacturer" ""
			(at 378.2 293.18 0)
			(layer "F.Fab")
			(hide yes)
			(effects
				(font
					(size 1 1)
					(thickness 0.15)
				)
			)
		)
		(sheetname "DC-DC Converters")
		(sheetfile "dc-dc.kicad_sch")
		(attr exclude_from_pos_files)
		(net_tie_pad_groups "1, 2")
		(fp_poly
			(pts
				(xy -0.0635 -0.0635) (xy 0.0625 -0.0635) (xy 0.0625 0.0635) (xy -0.0635 0.0635)
			)
			(stroke
				(width 0)
				(type solid)
			)
			(fill yes)
			(layer "F.Cu")
		)
		(pad "1" smd roundrect
			(at -0.127 0)
			(size 0.127 0.127)
			(layers "F.Cu")
			(roundrect_rratio 0.5)
			(chamfer_ratio 0)
			(chamfer top_left bottom_left)
			(net 1 "GND")
			(pinfunction "1")
			(pintype "passive")
		)
		(pad "2" smd roundrect
			(at 0.126 0 180)
			(size 0.127 0.127)
			(layers "F.Cu")
			(roundrect_rratio 0.5)
			(chamfer_ratio 0)
			(chamfer top_left bottom_left)
			(net 1215 "/DC-DC Converters/SENSE_1V35_N")
			(pinfunction "2")
			(pintype "passive")
		)
	)
	(footprint "antmicro-footprints:C_0603_1608Metric"
		(layer "F.Cu")
		(at 164.4 172.8 -90)
		(descr "Capacitor SMD 0603")
		(tags "capacitor 0603")
		(property "Reference" "C328"
			(at -1.36 -1.37 90)
			(layer "F.SilkS")
			(effects
				(font
					(size 0.7 0.7)
					(thickness 0.15)
				)
				(justify right bottom)
			)
		)
		(property "Value" "C_22u_0603"
			(at 0 1.6 90)
			(layer "F.Fab")
			(effects
				(font
					(size 0.7 0.7)
					(thickness 0.15)
				)
				(justify right bottom)
			)
		)
		(property "Description" "SMD Multilayer Ceramic Capacitor, 22 µF, 6.3 V, 0603 [1608 Metric], ± 20%, X5R, GRM Series"
			(at 0 0 270)
			(layer "F.Fab")
			(hide yes)
			(effects
				(font
					(size 1.27 1.27)
					(thickness 0.15)
				)
			)
		)
		(property "Author" "Antmicro"
			(at -8.4 337.2 0)
			(layer "F.Fab")
			(hide yes)
			(effects
				(font
					(size 1 1)
					(thickness 0.15)
				)
			)
		)
		(property "Dielectric" ""
			(at -8.4 337.2 0)
			(layer "F.Fab")
			(hide yes)
			(effects
				(font
					(size 1 1)
					(thickness 0.15)
				)
			)
		)
		(property "License" "Apache-2.0"
			(at -8.4 337.2 0)
			(layer "F.Fab")
			(hide yes)
			(effects
				(font
					(size 1 1)
					(thickness 0.15)
				)
			)
		)
		(property "MPN" "GRM188R60J226MEA0D"
			(at -8.4 337.2 0)
			(layer "F.Fab")
			(hide yes)
			(effects
				(font
					(size 1 1)
					(thickness 0.15)
				)
			)
		)
		(property "Manufacturer" "Murata"
			(at -8.4 337.2 0)
			(layer "F.Fab")
			(hide yes)
			(effects
				(font
					(size 1 1)
					(thickness 0.15)
				)
			)
		)
		(property "Val" "22u"
			(at -8.4 337.2 0)
			(layer "F.Fab")
			(hide yes)
			(effects
				(font
					(size 1 1)
					(thickness 0.15)
				)
			)
		)
		(property "Voltage" ""
			(at -8.4 337.2 0)
			(layer "F.Fab")
			(hide yes)
			(effects
				(font
					(size 1 1)
					(thickness 0.15)
				)
			)
		)
		(sheetname "DC-DC Converters")
		(sheetfile "dc-dc.kicad_sch")
		(attr smd)
		(fp_line
			(start -0.15 0.4)
			(end 0.15 0.4)
			(stroke
				(width 0.15)
				(type solid)
			)
			(layer "F.SilkS")
		)
		(fp_line
			(start -0.15 -0.4)
			(end 0.15 -0.4)
			(stroke
				(width 0.15)
				(type solid)
			)
			(layer "F.SilkS")
		)
		(fp_rect
			(start -1.25 -0.65)
			(end 1.25 0.65)
			(stroke
				(width 0.05)
				(type solid)
			)
			(fill no)
			(layer "F.CrtYd")
		)
		(fp_rect
			(start -0.8 -0.4)
			(end 0.8 0.4)
			(stroke
				(width 0.15)
				(type solid)
			)
			(fill no)
			(layer "F.Fab")
		)
		(pad "1" smd roundrect
			(at -0.7 0 270)
			(size 0.8 1)
			(layers "F.Cu" "F.Mask" "F.Paste")
			(roundrect_rratio 0.2)
			(net 1 "GND")
			(pintype "passive")
		)
		(pad "2" smd roundrect
			(at 0.7 0 270)
			(size 0.8 1)
			(layers "F.Cu" "F.Mask" "F.Paste")
			(roundrect_rratio 0.2)
			(net 737 "/DC-DC Converters/1V2_local")
			(pintype "passive")
		)
	)
	(footprint "antmicro-footprints:MPS_QFN-14_MP8869S"
		(layer "F.Cu")
		(at 194.598001 161.898999 180)
		(property "Reference" "U37"
			(at 3.898001 1.948999 180)
			(layer "F.SilkS")
			(effects
				(font
					(size 0.7 0.7)
					(thickness 0.15)
				)
				(justify left bottom)
			)
		)
		(property "Value" "MP8869S"
			(at -5.5 3.43 180)
			(layer "F.Fab")
			(effects
				(font
					(size 0.7 0.7)
					(thickness 0.15)
				)
				(justify left bottom)
			)
		)
		(property "Description" "DC-DC Switching Synchronous Buck Regulator, 2.85V-18V in, 600mV to 5.5V out, 12A, 500kHz, QFN-14"
			(at 0 0 180)
			(layer "F.Fab")
			(hide yes)
			(effects
				(font
					(size 1.27 1.27)
					(thickness 0.15)
				)
			)
		)
		(property "Author" "Antmicro"
			(at 389.196002 323.797998 0)
			(layer "F.Fab")
			(hide yes)
			(effects
				(font
					(size 1 1)
					(thickness 0.15)
				)
			)
		)
		(property "License" "Apache-2.0"
			(at 389.196002 323.797998 0)
			(layer "F.Fab")
			(hide yes)
			(effects
				(font
					(size 1 1)
					(thickness 0.15)
				)
			)
		)
		(property "MPN" "MP8869SGL-P"
			(at 389.196002 323.797998 0)
			(layer "F.Fab")
			(hide yes)
			(effects
				(font
					(size 1 1)
					(thickness 0.15)
				)
			)
		)
		(property "Manufacturer" "Monolithic Power Systems"
			(at 389.196002 323.797998 0)
			(layer "F.Fab")
			(hide yes)
			(effects
				(font
					(size 1 1)
					(thickness 0.15)
				)
			)
		)
		(sheetname "DC-DC Converters")
		(sheetfile "dc-dc.kicad_sch")
		(attr smd)
		(fp_line
			(start 1.675 0.981)
			(end 1.675 2.171)
			(stroke
				(width 0.15)
				(type solid)
			)
			(layer "F.SilkS")
		)
		(fp_line
			(start 1.675 -2.173)
			(end 1.675 -0.983)
			(stroke
				(width 0.15)
				(type solid)
			)
			(layer "F.SilkS")
		)
		(fp_line
			(start -1.678 2.171)
			(end -1.678 0.481)
			(stroke
				(width 0.15)
				(type solid)
			)
			(layer "F.SilkS")
		)
		(fp_line
			(start -1.678 -0.959)
			(end -1.678 -2.173)
			(stroke
				(width 0.15)
				(type solid)
			)
			(layer "F.SilkS")
		)
		(fp_circle
			(center -2.361 -0.5)
			(end -2.311 -0.5)
			(stroke
				(width 0.15)
				(type solid)
			)
			(fill yes)
			(layer "F.SilkS")
		)
		(fp_rect
			(start -2.061 -2.55)
			(end 2.06 2.548)
			(stroke
				(width 0.05)
				(type solid)
			)
			(fill no)
			(layer "F.CrtYd")
		)
		(fp_line
			(start 1.548 2.043)
			(end 1.548 -2.045)
			(stroke
				(width 0.15)
				(type solid)
			)
			(layer "F.Fab")
		)
		(fp_line
			(start 1.548 -2.045)
			(end -1.551 -2.045)
			(stroke
				(width 0.15)
				(type solid)
			)
			(layer "F.Fab")
		)
		(fp_line
			(start -1.541 -1.841)
			(end -1.341 -2.04)
			(stroke
				(width 0.15)
				(type solid)
			)
			(layer "F.Fab")
		)
		(fp_line
			(start -1.551 2.043)
			(end 1.548 2.043)
			(stroke
				(width 0.15)
				(type solid)
			)
			(layer "F.Fab")
		)
		(fp_line
			(start -1.551 -2.045)
			(end -1.551 2.043)
			(stroke
				(width 0.15)
				(type solid)
			)
			(layer "F.Fab")
		)
		(pad "1" smd custom
			(at -1.401 -0.5 180)
			(size 0.799998 0.249998)
			(layers "F.Cu" "F.Mask" "F.Paste")
			(net 745 "/DC-DC Converters/1V0_BS")
			(pinfunction "BST")
			(pintype "unspecified")
			(options
				(clearance outline)
				(anchor rect)
			)
			(primitives
				(gr_poly
					(pts
						(xy -0.400002 -0.125001) (xy -0.400002 0.124999) (xy 0.499998 0.124999) (xy 0.499998 -0.000001)
						(xy 0.374998 -0.125001)
					)
					(width 0.1)
					(fill yes)
				)
			)
		)
		(pad "2" smd rect
			(at -0.851 0 180)
			(size 1.9 0.3)
			(layers "F.Cu" "F.Mask" "F.Paste")
			(net 746 "/DC-DC Converters/1V0_SW")
			(pinfunction "SW")
			(pintype "output")
		)
		(pad "3" smd rect
			(at -1.002 1.848 270)
			(size 0.9 0.25)
			(layers "F.Cu" "F.Mask" "F.Paste")
			(net 1338 "/I2C.SCL")
			(pinfunction "SCL")
			(pintype "unspecified")
		)
		(pad "4" smd rect
			(at -0.5 1.848 270)
			(size 0.9 0.25)
			(layers "F.Cu" "F.Mask" "F.Paste")
			(net 1336 "/I2C.SDA")
			(pinfunction "SDA")
			(pintype "unspecified")
		)
		(pad "5" smd rect
			(at 0 1.848 270)
			(size 0.9 0.25)
			(layers "F.Cu" "F.Mask" "F.Paste")
			(net 966 "/DC-DC Converters/EN1")
			(pinfunction "EN")
			(pintype "unspecified")
		)
		(pad "6" smd rect
			(at 0.498 1.848 270)
			(size 0.9 0.25)
			(layers "F.Cu" "F.Mask" "F.Paste")
			(net 1 "GND")
			(pinfunction "A0")
			(pintype "unspecified")
		)
		(pad "7" smd rect
			(at 0.999 1.848 270)
			(size 0.9 0.25)
			(layers "F.Cu" "F.Mask" "F.Paste")
			(net 1389 "/SUP_MCU.PG_VCCINT")
			(pinfunction "PG")
			(pintype "unspecified")
		)
		(pad "8" smd custom
			(at 0.849 0.498 180)
			(size 0.127 0.127)
			(layers "F.Cu" "F.Mask" "F.Paste")
			(net 1 "GND")
			(pinfunction "PGND")
			(pintype "power_in")
			(options
				(clearance outline)
				(anchor rect)
			)
			(primitives
				(gr_poly
					(pts
						(xy 0.95 0.15) (xy 0.95 -0.15) (xy -0.55 -0.15) (xy -0.65 -0.05) (xy -0.95 -0.05) (xy -0.95 0.15)
					)
					(width 0.1)
					(fill yes)
				)
			)
		)
		(pad "9" smd custom
			(at 0.849 -0.5 180)
			(size 0.127 0.127)
			(layers "F.Cu" "F.Mask" "F.Paste")
			(net 702 "VDC")
			(pinfunction "VIN")
			(pintype "power_in")
			(options
				(clearance outline)
				(anchor rect)
			)
			(primitives
				(gr_poly
					(pts
						(xy 0.95 -0.15) (xy 0.95 0.15) (xy -0.55 0.15) (xy -0.65 0.05) (xy -0.95 0.05) (xy -0.95 -0.15)
					)
					(width 0.1)
					(fill yes)
				)
			)
		)
		(pad "10" smd rect
			(at 0.999 -1.851 270)
			(size 0.9 0.25)
			(layers "F.Cu" "F.Mask" "F.Paste")
			(net 751 "/DC-DC Converters/1V0_REG")
			(pinfunction "VOUT")
			(pintype "unspecified")
		)
		(pad "11" smd rect
			(at 0.498 -1.851 270)
			(size 0.9 0.25)
			(layers "F.Cu" "F.Mask" "F.Paste")
			(net 970 "/DC-DC Converters/1V0_FB")
			(pinfunction "FB")
			(pintype "unspecified")
		)
		(pad "12" smd rect
			(at 0 -1.851 270)
			(size 0.9 0.25)
			(layers "F.Cu" "F.Mask" "F.Paste")
			(net 749 "/DC-DC Converters/1V0_SS")
			(pinfunction "SS")
			(pintype "unspecified")
		)
		(pad "13" smd rect
			(at -0.5 -1.851 270)
			(size 0.9 0.25)
			(layers "F.Cu" "F.Mask" "F.Paste")
			(net 741 "/DC-DC Converters/1V0_VCC")
			(pinfunction "VCC")
			(pintype "power_out")
		)
		(pad "14" smd rect
			(at -1.002 -1.851 270)
			(size 0.9 0.25)
			(layers "F.Cu" "F.Mask" "F.Paste")
			(net 1 "GND")
			(pinfunction "AGND")
			(pintype "power_in")
		)
	)
)
